# SCM (Grand Teton) — schematic netlist excerpt (pin names and nets, part order shuffled) for the footprints in the layout excerpt that follows; sources: Cadence DE-HDL packaged netlist, KiCad conversion of 12092022_DA0F0TMDCD0_F0T_Management_Board_D_brd_V3_OCP.brd

J6  SCONN3_21291035BR2  SCONN3_212-91-035BR2 EMPTY  pkg HEADER1X3SXF  page 30
  \1\  = UART_BMC_5_TXD_BUF_R
  \2\  = GND
  \3\  = UART_BMC_5_RXD_BUF

R297  Q_RES  10K 1% CHIP  pkg 0402LF  page 34 : A = PU_PT20D ; B = VCCIO2

(kicad_pcb
	(version 20260206)
	(generator "pcbnew")
	(generator_version "10.0")
	(general
		(thickness 1.6)
		(legacy_teardrops no)
	)
	(paper "A4")
	(title_block
		(title "12092022_DA0F0TMDCD0_F0T_Management_Board_D_brd_V3_OCP.brd")
		(comment 1 "Grand Teton / footprints 408-409 of 1440")
	)
	(layers
		(0 "F.Cu" signal "TOP")
		(4 "In1.Cu" signal "GND")
		(6 "In2.Cu" signal "IN1")
		(8 "In3.Cu" signal "GND1")
		(10 "In4.Cu" signal "IN2")
		(12 "In5.Cu" signal "VCC")
		(14 "In6.Cu" signal "VCC1")
		(16 "In7.Cu" signal "IN3")
		(18 "In8.Cu" signal "GND2")
		(20 "In9.Cu" signal "IN4")
		(22 "In10.Cu" signal "GND3")
		(2 "B.Cu" signal "BOTTOM")
		(9 "F.Adhes" user "F.Adhesive")
		(11 "B.Adhes" user "B.Adhesive")
		(13 "F.Paste" user "Package Geometry/Pastemask Top")
		(15 "B.Paste" user "Package Geometry/Pastemask Bottom")
		(5 "F.SilkS" user "Ref Des/Silkscreen Top")
		(7 "B.SilkS" user "Ref Des/Silkscreen Bottom")
		(1 "F.Mask" user "Board Geometry/Soldermask Top")
		(3 "B.Mask" user "Board Geometry/Soldermask Bottom")
		(17 "Dwgs.User" user "User.Drawings")
		(19 "Cmts.User" user "User.Comments")
		(21 "Eco1.User" user "User.Eco1")
		(23 "Eco2.User" user "User.Eco2")
		(25 "Edge.Cuts" user "Board Geometry/Outline")
		(27 "Margin" user)
		(31 "F.CrtYd" user "Package Geometry/Place Bound Top")
		(29 "B.CrtYd" user "Package Geometry/Place Bound Bottom")
		(35 "F.Fab" user "Ref Des/Assembly Top")
		(33 "B.Fab" user "Ref Des/Assembly Bottom")
	)
	(footprint ""
		(layer "F.Cu")
		(at 12.875006 -25.146 180)
		(property "Reference" "J6"
			(at 4.6228 3.38963 0)
			(unlocked yes)
			(layer "F.SilkS")
			(effects
				(font
					(size 0.7874 0.5842)
					(thickness 0.1524)
				)
				(justify left)
			)
		)
		(property "Value" ""
			(at 0 0 180)
			(layer "F.Fab")
			(effects
				(font
					(size 1.27 1.27)
				)
			)
		)
		(duplicate_pad_numbers_are_jumpers no)
		(fp_line
			(start 1.249934 3.860038)
			(end 1.249934 3.1877)
			(stroke
				(width 0.1524)
				(type default)
			)
			(layer "F.SilkS")
		)
		(fp_line
			(start 1.249934 1.8923)
			(end 1.249934 -1.8923)
			(stroke
				(width 0.1524)
				(type default)
			)
			(layer "F.SilkS")
		)
		(fp_line
			(start 1.249934 -3.1877)
			(end 1.249934 -3.860038)
			(stroke
				(width 0.1524)
				(type default)
			)
			(layer "F.SilkS")
		)
		(fp_line
			(start 1.249934 -3.860038)
			(end -1.249934 -3.860038)
			(stroke
				(width 0.1524)
				(type default)
			)
			(layer "F.SilkS")
		)
		(fp_line
			(start -1.249934 3.860038)
			(end 1.249934 3.860038)
			(stroke
				(width 0.1524)
				(type default)
			)
			(layer "F.SilkS")
		)
		(fp_line
			(start -1.249934 0.6477)
			(end -1.249934 3.860038)
			(stroke
				(width 0.1524)
				(type default)
			)
			(layer "F.SilkS")
		)
		(fp_line
			(start -1.249934 -3.860038)
			(end -1.249934 -0.6477)
			(stroke
				(width 0.1524)
				(type default)
			)
			(layer "F.SilkS")
		)
		(fp_poly
			(pts
				(xy 2.413 -5.334) (xy 1.397 -5.334) (xy 1.905 -4.318)
			)
			(stroke
				(width 0)
				(type default)
			)
			(fill yes)
			(layer "F.SilkS")
		)
		(fp_line
			(start 1.249934 3.860038)
			(end 1.249934 -3.860038)
			(stroke
				(width 0.1)
				(type default)
			)
			(layer "F.Fab")
		)
		(fp_line
			(start 1.249934 -3.860038)
			(end -1.249934 -3.860038)
			(stroke
				(width 0.1)
				(type default)
			)
			(layer "F.Fab")
		)
		(fp_line
			(start -1.249934 3.860038)
			(end 1.249934 3.860038)
			(stroke
				(width 0.1)
				(type default)
			)
			(layer "F.Fab")
		)
		(fp_line
			(start -1.249934 -3.860038)
			(end -1.249934 3.860038)
			(stroke
				(width 0.1)
				(type default)
			)
			(layer "F.Fab")
		)
		(fp_poly
			(pts
				(xy 4.281678 -2.032) (xy 4.281678 -3.048) (xy 3.265678 -2.54)
			)
			(stroke
				(width 0)
				(type default)
			)
			(fill yes)
			(layer "F.Fab")
		)
		(pad "1" smd rect
			(at 1.374902 -2.54 90)
			(size 1.016 2.7686)
			(layers "F.Cu" "F.Mask" "F.Paste")
			(net "UART_BMC_5_TXD_BUF_R")
		)
		(pad "2" smd rect
			(at -1.374902 0 90)
			(size 1.016 2.7686)
			(layers "F.Cu" "F.Mask" "F.Paste")
			(net "GND")
		)
		(pad "3" smd rect
			(at 1.374902 2.54 90)
			(size 1.016 2.7686)
			(layers "F.Cu" "F.Mask" "F.Paste")
			(net "UART_BMC_5_RXD_BUF")
		)
	)
	(footprint ""
		(layer "F.Cu")
		(at 19.431 -83.72602 -90)
		(property "Reference" "R297"
			(at 0 0 270)
			(layer "F.SilkS")
			(hide yes)
			(effects
				(font
					(size 1.27 1.27)
				)
			)
		)
		(property "Value" ""
			(at 0 0 270)
			(layer "F.Fab")
			(effects
				(font
					(size 1.27 1.27)
				)
			)
		)
		(duplicate_pad_numbers_are_jumpers no)
		(fp_line
			(start -0.7874 0.4064)
			(end -0.7874 -0.4064)
			(stroke
				(width 0.1524)
				(type default)
			)
			(layer "F.SilkS")
		)
		(fp_line
			(start 0.7874 0.4064)
			(end -0.7874 0.4064)
			(stroke
				(width 0.1524)
				(type default)
			)
			(layer "F.SilkS")
		)
		(fp_line
			(start -0.7874 -0.4064)
			(end 0.7874 -0.4064)
			(stroke
				(width 0.1524)
				(type default)
			)
			(layer "F.SilkS")
		)
		(fp_line
			(start 0.7874 -0.4064)
			(end 0.7874 0.4064)
			(stroke
				(width 0.1524)
				(type default)
			)
			(layer "F.SilkS")
		)
		(fp_line
			(start -0.67945 0.3048)
			(end -0.67945 -0.305054)
			(stroke
				(width 0.1)
				(type default)
			)
			(layer "F.Fab")
		)
		(fp_line
			(start -0.12065 0.3048)
			(end -0.67945 0.3048)
			(stroke
				(width 0.1)
				(type default)
			)
			(layer "F.Fab")
		)
		(fp_line
			(start 0.120396 0.3048)
			(end 0.120396 0.2794)
			(stroke
				(width 0.1)
				(type default)
			)
			(layer "F.Fab")
		)
		(fp_line
			(start 0.67945 0.3048)
			(end 0.120396 0.3048)
			(stroke
				(width 0.1)
				(type default)
			)
			(layer "F.Fab")
		)
		(fp_line
			(start -0.12065 0.2794)
			(end -0.12065 0.3048)
			(stroke
				(width 0.1)
				(type default)
			)
			(layer "F.Fab")
		)
		(fp_line
			(start 0.120396 0.2794)
			(end -0.12065 0.2794)
			(stroke
				(width 0.1)
				(type default)
			)
			(layer "F.Fab")
		)
		(fp_line
			(start -0.12065 -0.2794)
			(end 0.12065 -0.2794)
			(stroke
				(width 0.1)
				(type default)
			)
			(layer "F.Fab")
		)
		(fp_line
			(start 0.12065 -0.2794)
			(end 0.12065 -0.3048)
			(stroke
				(width 0.1)
				(type default)
			)
			(layer "F.Fab")
		)
		(fp_line
			(start 0.12065 -0.3048)
			(end 0.67945 -0.3048)
			(stroke
				(width 0.1)
				(type default)
			)
			(layer "F.Fab")
		)
		(fp_line
			(start 0.67945 -0.3048)
			(end 0.67945 0.3048)
			(stroke
				(width 0.1)
				(type default)
			)
			(layer "F.Fab")
		)
		(fp_line
			(start -0.67945 -0.305054)
			(end -0.12065 -0.305054)
			(stroke
				(width 0.1)
				(type default)
			)
			(layer "F.Fab")
		)
		(fp_line
			(start -0.12065 -0.305054)
			(end -0.12065 -0.2794)
			(stroke
				(width 0.1)
				(type default)
			)
			(layer "F.Fab")
		)
		(pad "1" smd circle
			(at -0.40005 0 270)
			(size 0 0)
			(layers "F.Cu" "F.Mask" "F.Paste")
			(net "PU_PT20D")
		)
		(pad "2" smd circle
			(at 0.40005 0 270)
			(size 0 0)
			(layers "F.Cu" "F.Mask" "F.Paste")
			(net "VCCIO2")
		)
	)
)
